# S9S_MB_2U (Grand Teton) — schematic netlist excerpt (pin names and nets, part order shuffled) for the footprints in the layout excerpt that follows; sources: Cadence DE-HDL packaged netlist, KiCad conversion of 03242023_DA0F0TMBIJ0_F0T_Motherboard_J_brd_V01_OCP.brd

R1453  Q_RES  2K 1% CHIP  pkg 0402LF  page 183 : A = PU_SMB_SML4_3V3AUX_PCH_SCL ; B = P3V3_AUX
PC83  Q_CAPP  560UF 2.5V 20% OSCON  pkg THLF  page 285 : A = PVCCIN_CPU1 ; B = GND
PC2157  Q_CAP  39PF 50V 5% EMPTY  pkg C0402  page 157 : A = P3V3_OCP_MODE_1 ; B = GND

(kicad_pcb
	(version 20260206)
	(generator "pcbnew")
	(generator_version "10.0")
	(general
		(thickness 1.6)
		(legacy_teardrops no)
	)
	(paper "A4")
	(title_block
		(title "03242023_DA0F0TMBIJ0_F0T_Motherboard_J_brd_V01_OCP.brd")
		(comment 1 "Grand Teton / footprints 3849-3851 of 6105")
	)
	(layers
		(0 "F.Cu" signal "TOP")
		(4 "In1.Cu" signal "GND")
		(6 "In2.Cu" signal "IN1")
		(8 "In3.Cu" signal "GND1")
		(10 "In4.Cu" signal "IN2")
		(12 "In5.Cu" signal "GND2")
		(14 "In6.Cu" signal "IN3")
		(16 "In7.Cu" signal "GND3")
		(18 "In8.Cu" signal "VCC")
		(20 "In9.Cu" signal "VCC1")
		(22 "In10.Cu" signal "GND4")
		(24 "In11.Cu" signal "IN4")
		(26 "In12.Cu" signal "GND5")
		(28 "In13.Cu" signal "IN5")
		(30 "In14.Cu" signal "GND6")
		(32 "In15.Cu" signal "IN6")
		(34 "In16.Cu" signal "GND7")
		(2 "B.Cu" signal "BOTTOM")
		(9 "F.Adhes" user "F.Adhesive")
		(11 "B.Adhes" user "B.Adhesive")
		(13 "F.Paste" user "Package Geometry/Pastemask Top")
		(15 "B.Paste" user "Package Geometry/Pastemask Bottom")
		(5 "F.SilkS" user "Ref Des/Silkscreen Top")
		(7 "B.SilkS" user "Ref Des/Silkscreen Bottom")
		(1 "F.Mask" user "Board Geometry/Soldermask Top")
		(3 "B.Mask" user "Board Geometry/Soldermask Bottom")
		(17 "Dwgs.User" user "User.Drawings")
		(19 "Cmts.User" user "User.Comments")
		(21 "Eco1.User" user "User.Eco1")
		(23 "Eco2.User" user "User.Eco2")
		(25 "Edge.Cuts" user "Board Geometry/Outline")
		(27 "Margin" user)
		(31 "F.CrtYd" user "Package Geometry/Place Bound Top")
		(29 "B.CrtYd" user "Package Geometry/Place Bound Bottom")
		(35 "F.Fab" user "Ref Des/Assembly Top")
		(33 "B.Fab" user "Ref Des/Assembly Bottom")
	)
	(footprint ""
		(layer "F.Cu")
		(at 313.535314 -27.078686 180)
		(property "Reference" "R1453"
			(at 0 0 180)
			(layer "F.SilkS")
			(hide yes)
			(effects
				(font
					(size 1.27 1.27)
				)
			)
		)
		(property "Value" ""
			(at 0 0 180)
			(layer "F.Fab")
			(effects
				(font
					(size 1.27 1.27)
				)
			)
		)
		(duplicate_pad_numbers_are_jumpers no)
		(fp_line
			(start 0.7874 0.4064)
			(end -0.7874 0.4064)
			(stroke
				(width 0.1524)
				(type default)
			)
			(layer "F.SilkS")
		)
		(fp_line
			(start 0.7874 -0.4064)
			(end 0.7874 0.4064)
			(stroke
				(width 0.1524)
				(type default)
			)
			(layer "F.SilkS")
		)
		(fp_line
			(start -0.7874 0.4064)
			(end -0.7874 -0.4064)
			(stroke
				(width 0.1524)
				(type default)
			)
			(layer "F.SilkS")
		)
		(fp_line
			(start -0.7874 -0.4064)
			(end 0.7874 -0.4064)
			(stroke
				(width 0.1524)
				(type default)
			)
			(layer "F.SilkS")
		)
		(fp_line
			(start 0.67945 0.3048)
			(end 0.120396 0.3048)
			(stroke
				(width 0.1)
				(type default)
			)
			(layer "F.Fab")
		)
		(fp_line
			(start 0.67945 -0.3048)
			(end 0.67945 0.3048)
			(stroke
				(width 0.1)
				(type default)
			)
			(layer "F.Fab")
		)
		(fp_line
			(start 0.12065 -0.2794)
			(end 0.12065 -0.3048)
			(stroke
				(width 0.1)
				(type default)
			)
			(layer "F.Fab")
		)
		(fp_line
			(start 0.12065 -0.3048)
			(end 0.67945 -0.3048)
			(stroke
				(width 0.1)
				(type default)
			)
			(layer "F.Fab")
		)
		(fp_line
			(start 0.120396 0.3048)
			(end 0.120396 0.2794)
			(stroke
				(width 0.1)
				(type default)
			)
			(layer "F.Fab")
		)
		(fp_line
			(start 0.120396 0.2794)
			(end -0.12065 0.2794)
			(stroke
				(width 0.1)
				(type default)
			)
			(layer "F.Fab")
		)
		(fp_line
			(start -0.12065 0.3048)
			(end -0.67945 0.3048)
			(stroke
				(width 0.1)
				(type default)
			)
			(layer "F.Fab")
		)
		(fp_line
			(start -0.12065 0.2794)
			(end -0.12065 0.3048)
			(stroke
				(width 0.1)
				(type default)
			)
			(layer "F.Fab")
		)
		(fp_line
			(start -0.12065 -0.2794)
			(end 0.12065 -0.2794)
			(stroke
				(width 0.1)
				(type default)
			)
			(layer "F.Fab")
		)
		(fp_line
			(start -0.12065 -0.305054)
			(end -0.12065 -0.2794)
			(stroke
				(width 0.1)
				(type default)
			)
			(layer "F.Fab")
		)
		(fp_line
			(start -0.67945 0.3048)
			(end -0.67945 -0.305054)
			(stroke
				(width 0.1)
				(type default)
			)
			(layer "F.Fab")
		)
		(fp_line
			(start -0.67945 -0.305054)
			(end -0.12065 -0.305054)
			(stroke
				(width 0.1)
				(type default)
			)
			(layer "F.Fab")
		)
		(pad "1" smd circle
			(at -0.40005 0 180)
			(size 0 0)
			(layers "F.Cu" "F.Mask" "F.Paste")
			(net "PU_SMB_SML4_3V3AUX_PCH_SCL")
		)
		(pad "2" smd circle
			(at 0.40005 0 180)
			(size 0 0)
			(layers "F.Cu" "F.Mask" "F.Paste")
			(net "P3V3_AUX")
		)
	)
	(footprint ""
		(layer "F.Cu")
		(at 421.54094 -101.270308 -90)
		(property "Reference" "PC2157"
			(at 0 0 270)
			(layer "F.SilkS")
			(hide yes)
			(effects
				(font
					(size 1.27 1.27)
				)
			)
		)
		(property "Value" ""
			(at 0 0 270)
			(layer "F.Fab")
			(effects
				(font
					(size 1.27 1.27)
				)
			)
		)
		(duplicate_pad_numbers_are_jumpers no)
		(fp_line
			(start -0.7874 0.4064)
			(end -0.7874 -0.4064)
			(stroke
				(width 0.1524)
				(type default)
			)
			(layer "F.SilkS")
		)
		(fp_line
			(start 0.7874 0.4064)
			(end -0.7874 0.4064)
			(stroke
				(width 0.1524)
				(type default)
			)
			(layer "F.SilkS")
		)
		(fp_line
			(start -0.7874 -0.4064)
			(end 0.7874 -0.4064)
			(stroke
				(width 0.1524)
				(type default)
			)
			(layer "F.SilkS")
		)
		(fp_line
			(start 0.7874 -0.4064)
			(end 0.7874 0.4064)
			(stroke
				(width 0.1524)
				(type default)
			)
			(layer "F.SilkS")
		)
		(fp_line
			(start -0.67945 0.3048)
			(end -0.67945 -0.305054)
			(stroke
				(width 0.1)
				(type default)
			)
			(layer "F.Fab")
		)
		(fp_line
			(start -0.12065 0.3048)
			(end -0.67945 0.3048)
			(stroke
				(width 0.1)
				(type default)
			)
			(layer "F.Fab")
		)
		(fp_line
			(start 0.120396 0.3048)
			(end 0.120396 0.2794)
			(stroke
				(width 0.1)
				(type default)
			)
			(layer "F.Fab")
		)
		(fp_line
			(start 0.67945 0.3048)
			(end 0.120396 0.3048)
			(stroke
				(width 0.1)
				(type default)
			)
			(layer "F.Fab")
		)
		(fp_line
			(start -0.12065 0.2794)
			(end -0.12065 0.3048)
			(stroke
				(width 0.1)
				(type default)
			)
			(layer "F.Fab")
		)
		(fp_line
			(start 0.120396 0.2794)
			(end -0.12065 0.2794)
			(stroke
				(width 0.1)
				(type default)
			)
			(layer "F.Fab")
		)
		(fp_line
			(start -0.12065 -0.2794)
			(end 0.12065 -0.2794)
			(stroke
				(width 0.1)
				(type default)
			)
			(layer "F.Fab")
		)
		(fp_line
			(start 0.12065 -0.2794)
			(end 0.12065 -0.3048)
			(stroke
				(width 0.1)
				(type default)
			)
			(layer "F.Fab")
		)
		(fp_line
			(start 0.12065 -0.3048)
			(end 0.67945 -0.3048)
			(stroke
				(width 0.1)
				(type default)
			)
			(layer "F.Fab")
		)
		(fp_line
			(start 0.67945 -0.3048)
			(end 0.67945 0.3048)
			(stroke
				(width 0.1)
				(type default)
			)
			(layer "F.Fab")
		)
		(fp_line
			(start -0.67945 -0.305054)
			(end -0.12065 -0.305054)
			(stroke
				(width 0.1)
				(type default)
			)
			(layer "F.Fab")
		)
		(fp_line
			(start -0.12065 -0.305054)
			(end -0.12065 -0.2794)
			(stroke
				(width 0.1)
				(type default)
			)
			(layer "F.Fab")
		)
		(pad "1" smd circle
			(at -0.40005 0 270)
			(size 0 0)
			(layers "F.Cu" "F.Mask" "F.Paste")
			(net "P3V3_OCP_MODE_1")
		)
		(pad "2" smd circle
			(at 0.40005 0 270)
			(size 0 0)
			(layers "F.Cu" "F.Mask" "F.Paste")
			(net "GND")
		)
	)
	(footprint ""
		(layer "F.Cu")
		(at 123.296426 -315.66739 90)
		(property "Reference" "PC83"
			(at 0 0 90)
			(layer "F.SilkS")
			(hide yes)
			(effects
				(font
					(size 1.27 1.27)
				)
			)
		)
		(property "Value" ""
			(at 0 0 90)
			(layer "F.Fab")
			(effects
				(font
					(size 1.27 1.27)
				)
			)
		)
		(duplicate_pad_numbers_are_jumpers no)
		(fp_line
			(start 2.750058 0.999998)
			(end -2.750058 0.999998)
			(stroke
				(width 0.1524)
				(type default)
			)
			(layer "F.SilkS")
		)
		(fp_circle
			(center 0 0.999998)
			(end 0 3.750056)
			(stroke
				(width 0.1524)
				(type default)
			)
			(fill no)
			(layer "F.SilkS")
		)
		(fp_poly
			(pts
				(arc
					(start 2.750058 0.999998)
					(mid 0 3.750056)
					(end -2.750058 0.999998)
				)
			)
			(stroke
				(width 0)
				(type default)
			)
			(fill yes)
			(layer "F.SilkS")
		)
		(fp_circle
			(center 0 0.999998)
			(end 0 3.750056)
			(stroke
				(width 0.1)
				(type default)
			)
			(fill no)
			(layer "F.Fab")
		)
		(pad "1" thru_hole rect
			(at 0 0 90)
			(size 1.5748 1.5748)
			(drill 1.0668)
			(layers "*.Cu" "*.Mask")
			(remove_unused_layers no)
			(net "PVCCIN_CPU1")
			(clearance 0)
			(padstack
				(mode front_inner_back)
				(layer "Inner"
					(shape circle)
					(size 1.5748 1.5748)
					(clearance 0)
				)
				(layer "B.Cu"
					(shape rect)
					(size 1.5748 1.5748)
					(clearance 0)
				)
			)
		)
		(pad "2" thru_hole circle
			(at 0 1.999996 90)
			(size 1.5748 1.5748)
			(drill 1.0668)
			(layers "*.Cu" "*.Mask")
			(remove_unused_layers no)
			(net "GND")
			(clearance 0)
		)
	)
)
